(kicad_pcb
	(version 20260206)
	(generator "pcbnew")
	(generator_version "10.0")
	(general
		(thickness 1.6)
		(legacy_teardrops no)
	)
	(paper "A4")
	(title_block
		(title "01162023_DA0F0TEBIF0_F0T_Expander_BD_F_brd_V02_OCP.brd")
		(comment 1 "Grand Teton / footprints 4972-4976 of 9728")
	)
	(layers
		(0 "F.Cu" signal "TOP")
		(4 "In1.Cu" signal "GND")
		(6 "In2.Cu" signal "VCC")
		(8 "In3.Cu" signal "VCC1")
		(10 "In4.Cu" signal "GND1")
		(12 "In5.Cu" signal "IN1")
		(14 "In6.Cu" signal "GND2")
		(16 "In7.Cu" signal "IN2")
		(18 "In8.Cu" signal "GND3")
		(20 "In9.Cu" signal "IN3")
		(22 "In10.Cu" signal "GND4")
		(24 "In11.Cu" signal "IN4")
		(26 "In12.Cu" signal "GND5")
		(28 "In13.Cu" signal "IN5")
		(30 "In14.Cu" signal "GND6")
		(32 "In15.Cu" signal "IN6")
		(34 "In16.Cu" signal "GND7")
		(2 "B.Cu" signal "BOTTOM")
		(9 "F.Adhes" user "F.Adhesive")
		(11 "B.Adhes" user "B.Adhesive")
		(13 "F.Paste" user "Package Geometry/Pastemask Top")
		(15 "B.Paste" user "Package Geometry/Pastemask Bottom")
		(5 "F.SilkS" user "Ref Des/Silkscreen Top")
		(7 "B.SilkS" user "Ref Des/Silkscreen Bottom")
		(1 "F.Mask" user "Board Geometry/Soldermask Top")
		(3 "B.Mask" user "Board Geometry/Soldermask Bottom")
		(17 "Dwgs.User" user "User.Drawings")
		(19 "Cmts.User" user "User.Comments")
		(21 "Eco1.User" user "User.Eco1")
		(23 "Eco2.User" user "User.Eco2")
		(25 "Edge.Cuts" user "Board Geometry/Outline")
		(27 "Margin" user)
		(31 "F.CrtYd" user "Package Geometry/Place Bound Top")
		(29 "B.CrtYd" user "Package Geometry/Place Bound Bottom")
		(35 "F.Fab" user "Ref Des/Assembly Top")
		(33 "B.Fab" user "Ref Des/Assembly Bottom")
	)
	(footprint ""
		(layer "F.Cu")
		(at 97.654618 -22.867366 90)
		(property "Reference" "C3898"
			(at 0 0 90)
			(layer "F.SilkS")
			(hide yes)
			(effects
				(font
					(size 1.27 1.27)
				)
			)
		)
		(property "Value" ""
			(at 0 0 90)
			(layer "F.Fab")
			(effects
				(font
					(size 1.27 1.27)
				)
			)
		)
		(duplicate_pad_numbers_are_jumpers no)
		(fp_line
			(start 0.7874 -0.4064)
			(end 0.7874 0.4064)
			(stroke
				(width 0.1524)
				(type default)
			)
			(layer "F.SilkS")
		)
		(fp_line
			(start -0.7874 -0.4064)
			(end 0.7874 -0.4064)
			(stroke
				(width 0.1524)
				(type default)
			)
			(layer "F.SilkS")
		)
		(fp_line
			(start 0.7874 0.4064)
			(end -0.7874 0.4064)
			(stroke
				(width 0.1524)
				(type default)
			)
			(layer "F.SilkS")
		)
		(fp_line
			(start -0.7874 0.4064)
			(end -0.7874 -0.4064)
			(stroke
				(width 0.1524)
				(type default)
			)
			(layer "F.SilkS")
		)
		(fp_line
			(start -0.12065 -0.305054)
			(end -0.12065 -0.2794)
			(stroke
				(width 0.1)
				(type default)
			)
			(layer "F.Fab")
		)
		(fp_line
			(start -0.67945 -0.305054)
			(end -0.12065 -0.305054)
			(stroke
				(width 0.1)
				(type default)
			)
			(layer "F.Fab")
		)
		(fp_line
			(start 0.67945 -0.3048)
			(end 0.67945 0.3048)
			(stroke
				(width 0.1)
				(type default)
			)
			(layer "F.Fab")
		)
		(fp_line
			(start 0.12065 -0.3048)
			(end 0.67945 -0.3048)
			(stroke
				(width 0.1)
				(type default)
			)
			(layer "F.Fab")
		)
		(fp_line
			(start 0.12065 -0.2794)
			(end 0.12065 -0.3048)
			(stroke
				(width 0.1)
				(type default)
			)
			(layer "F.Fab")
		)
		(fp_line
			(start -0.12065 -0.2794)
			(end 0.12065 -0.2794)
			(stroke
				(width 0.1)
				(type default)
			)
			(layer "F.Fab")
		)
		(fp_line
			(start 0.120396 0.2794)
			(end -0.12065 0.2794)
			(stroke
				(width 0.1)
				(type default)
			)
			(layer "F.Fab")
		)
		(fp_line
			(start -0.12065 0.2794)
			(end -0.12065 0.3048)
			(stroke
				(width 0.1)
				(type default)
			)
			(layer "F.Fab")
		)
		(fp_line
			(start 0.67945 0.3048)
			(end 0.120396 0.3048)
			(stroke
				(width 0.1)
				(type default)
			)
			(layer "F.Fab")
		)
		(fp_line
			(start 0.120396 0.3048)
			(end 0.120396 0.2794)
			(stroke
				(width 0.1)
				(type default)
			)
			(layer "F.Fab")
		)
		(fp_line
			(start -0.12065 0.3048)
			(end -0.67945 0.3048)
			(stroke
				(width 0.1)
				(type default)
			)
			(layer "F.Fab")
		)
		(fp_line
			(start -0.67945 0.3048)
			(end -0.67945 -0.305054)
			(stroke
				(width 0.1)
				(type default)
			)
			(layer "F.Fab")
		)
		(pad "1" smd circle
			(at -0.40005 0 90)
			(size 0 0)
			(layers "F.Cu" "F.Mask" "F.Paste")
			(net "P12V_SSD3")
		)
		(pad "2" smd circle
			(at 0.40005 0 90)
			(size 0 0)
			(layers "F.Cu" "F.Mask" "F.Paste")
			(net "GND")
		)
	)
	(footprint ""
		(layer "F.Cu")
		(at 339.812884 -111.785654 180)
		(property "Reference" "PU104"
			(at 3.922014 -2.311654 90)
			(unlocked yes)
			(layer "F.SilkS")
			(effects
				(font
					(size 0.7874 0.5842)
					(thickness 0.1524)
				)
				(justify left)
			)
		)
		(property "Value" ""
			(at 0 0 180)
			(layer "F.Fab")
			(effects
				(font
					(size 1.27 1.27)
				)
			)
		)
		(duplicate_pad_numbers_are_jumpers no)
		(fp_line
			(start 1.549908 2.549906)
			(end 1.549908 2.253996)
			(stroke
				(width 0.1524)
				(type default)
			)
			(layer "F.SilkS")
		)
		(fp_line
			(start 1.549908 -2.253996)
			(end 1.549908 -2.549906)
			(stroke
				(width 0.1524)
				(type default)
			)
			(layer "F.SilkS")
		)
		(fp_line
			(start 1.549908 -2.549906)
			(end 0.752094 -2.549906)
			(stroke
				(width 0.1524)
				(type default)
			)
			(layer "F.SilkS")
		)
		(fp_line
			(start 0.753872 2.549906)
			(end 1.549908 2.549906)
			(stroke
				(width 0.1524)
				(type default)
			)
			(layer "F.SilkS")
		)
		(fp_line
			(start 0.2413 -2.549906)
			(end -0.2413 -2.549906)
			(stroke
				(width 0.1524)
				(type default)
			)
			(layer "F.SilkS")
		)
		(fp_line
			(start -0.245872 2.549906)
			(end 0.245872 2.549906)
			(stroke
				(width 0.1524)
				(type default)
			)
			(layer "F.SilkS")
		)
		(fp_line
			(start -0.752094 -2.549906)
			(end -1.549908 -2.549906)
			(stroke
				(width 0.1524)
				(type default)
			)
			(layer "F.SilkS")
		)
		(fp_line
			(start -1.549908 2.549906)
			(end -0.753872 2.549906)
			(stroke
				(width 0.1524)
				(type default)
			)
			(layer "F.SilkS")
		)
		(fp_line
			(start -1.549908 2.253996)
			(end -1.549908 2.549906)
			(stroke
				(width 0.1524)
				(type default)
			)
			(layer "F.SilkS")
		)
		(fp_line
			(start -1.549908 -2.549906)
			(end -1.549908 -2.251964)
			(stroke
				(width 0.1524)
				(type default)
			)
			(layer "F.SilkS")
		)
		(fp_poly
			(pts
				(xy -2.38506 -1.744218) (xy -3.288284 -2.045462) (xy -2.686304 -2.647442)
			)
			(stroke
				(width 0)
				(type default)
			)
			(fill yes)
			(layer "F.SilkS")
		)
		(fp_line
			(start 1.549908 2.549906)
			(end 1.549908 -2.549906)
			(stroke
				(width 0.1)
				(type default)
			)
			(layer "F.Fab")
		)
		(fp_line
			(start 1.549908 -2.549906)
			(end -1.549908 -2.549906)
			(stroke
				(width 0.1)
				(type default)
			)
			(layer "F.Fab")
		)
		(fp_line
			(start -1.549908 2.549906)
			(end 1.549908 2.549906)
			(stroke
				(width 0.1)
				(type default)
			)
			(layer "F.Fab")
		)
		(fp_line
			(start -1.549908 -2.549906)
			(end -1.549908 2.549906)
			(stroke
				(width 0.1)
				(type default)
			)
			(layer "F.Fab")
		)
		(fp_poly
			(pts
				(xy -1.891538 -1.999996) (xy -2.7432 -1.574292) (xy -2.7432 -2.4257)
			)
			(stroke
				(width 0)
				(type default)
			)
			(fill yes)
			(layer "F.Fab")
		)
		(fp_text user "12"
			(at 2.456434 1.083056 90)
			(unlocked yes)
			(layer "F.SilkS")
			(effects
				(font
					(size 0.635 0.4064)
					(thickness 0.1524)
				)
			)
		)
		(fp_text user "20"
			(at 2.055368 -2.7686 90)
			(unlocked yes)
			(layer "F.SilkS")
			(effects
				(font
					(size 0.635 0.4064)
					(thickness 0.1524)
				)
			)
		)
		(fp_text user "11"
			(at 1.308862 3.031998 0)
			(unlocked yes)
			(layer "F.SilkS")
			(effects
				(font
					(size 0.635 0.4064)
					(thickness 0.1524)
				)
			)
		)
		(fp_text user "21_22"
			(at -1.198372 -3.315208 0)
			(unlocked yes)
			(layer "F.SilkS")
			(effects
				(font
					(size 0.635 0.4064)
					(thickness 0.1524)
				)
			)
		)
		(fp_text user "10"
			(at -1.438148 2.983738 0)
			(unlocked yes)
			(layer "F.SilkS")
			(effects
				(font
					(size 0.635 0.4064)
					(thickness 0.1524)
				)
			)
		)
		(fp_text user "9"
			(at -2.19456 2.16535 0)
			(unlocked yes)
			(layer "F.SilkS")
			(effects
				(font
					(size 0.635 0.4064)
					(thickness 0.1524)
				)
			)
		)
		(fp_text user "12"
			(at 2.207768 2.7178 90)
			(unlocked yes)
			(layer "F.Fab")
			(effects
				(font
					(size 0.635 0.4064)
					(thickness 0.1524)
				)
			)
		)
		(fp_text user "20"
			(at 2.055368 -2.7686 90)
			(unlocked yes)
			(layer "F.Fab")
			(effects
				(font
					(size 0.635 0.4064)
					(thickness 0.1524)
				)
			)
		)
		(fp_text user "11"
			(at 1.1938 3.329432 180)
			(unlocked yes)
			(layer "F.Fab")
			(effects
				(font
					(size 0.635 0.4064)
					(thickness 0.1524)
				)
			)
		)
		(fp_text user "21_22"
			(at -0.0762 -3.401568 180)
			(unlocked yes)
			(layer "F.Fab")
			(effects
				(font
					(size 0.635 0.4064)
					(thickness 0.1524)
				)
			)
		)
		(fp_text user "10"
			(at -1.4224 3.253232 180)
			(unlocked yes)
			(layer "F.Fab")
			(effects
				(font
					(size 0.635 0.4064)
					(thickness 0.1524)
				)
			)
		)
		(fp_text user "9"
			(at -2.338832 2.5908 90)
			(unlocked yes)
			(layer "F.Fab")
			(effects
				(font
					(size 0.635 0.4064)
					(thickness 0.1524)
				)
			)
		)
		(pad "1" smd circle
			(at -1.374902 -1.999996 90)
			(size 0 0)
			(layers "F.Cu" "F.Mask" "F.Paste")
			(net "P12V_NIC5_CO_EN")
		)
		(pad "2" smd rect
			(at -1.400048 -1.500124 90)
			(size 0.254 0.8128)
			(layers "F.Cu" "F.Mask" "F.Paste")
			(net "GND")
		)
		(pad "3" smd rect
			(at -1.400048 -0.999998 90)
			(size 0.254 0.8128)
			(layers "F.Cu" "F.Mask" "F.Paste")
			(net "GND")
		)
		(pad "4" smd rect
			(at -1.400048 -0.499872 90)
			(size 0.254 0.8128)
			(layers "F.Cu" "F.Mask" "F.Paste")
			(net "P12V_NIC5_CO_TIMER")
		)
		(pad "5" smd rect
			(at -1.400048 0 90)
			(size 0.254 0.8128)
			(layers "F.Cu" "F.Mask" "F.Paste")
			(net "P12V_NIC5_CO_ISET")
		)
		(pad "6" smd rect
			(at -1.400048 0.499872 90)
			(size 0.254 0.8128)
			(layers "F.Cu" "F.Mask" "F.Paste")
			(net "P12V_NIC5_CO_SS")
		)
		(pad "7" smd rect
			(at -1.400048 0.999998 90)
			(size 0.254 0.8128)
			(layers "F.Cu" "F.Mask" "F.Paste")
			(net "GND")
		)
		(pad "8" smd rect
			(at -1.400048 1.500124 90)
			(size 0.254 0.8128)
			(layers "F.Cu" "F.Mask" "F.Paste")
			(net "P12V_NIC5_CO_IMON_VR")
		)
		(pad "9" smd rect
			(at -1.400048 1.999996 90)
			(size 0.254 0.8128)
			(layers "F.Cu" "F.Mask" "F.Paste")
			(net "P12V_NIC5_CO_FLTB")
		)
		(pad "10" smd rect
			(at -0.499872 2.400046 180)
			(size 0.254 0.8128)
			(layers "F.Cu" "F.Mask" "F.Paste")
			(net "PWRGD_P12V_NIC5_CO")
		)
		(pad "11" smd rect
			(at 0.499872 2.400046 180)
			(size 0.254 0.8128)
			(layers "F.Cu" "F.Mask" "F.Paste")
			(net "P12V_NIC5_CO_OV_FB")
		)
		(pad "12" smd rect
			(at 1.400048 1.999996 90)
			(size 0.254 0.8128)
			(layers "F.Cu" "F.Mask" "F.Paste")
			(net "P12V_NIC5_CO_AVIN_PD")
		)
		(pad "13" smd rect
			(at 1.400048 1.500124 90)
			(size 0.254 0.8128)
			(layers "F.Cu" "F.Mask" "F.Paste")
			(net "P12V_NIC5_R")
		)
		(pad "14" smd rect
			(at 1.400048 0.999998 90)
			(size 0.254 0.8128)
			(layers "F.Cu" "F.Mask" "F.Paste")
			(net "P12V_NIC5_R")
		)
		(pad "15" smd rect
			(at 1.400048 0.499872 90)
			(size 0.254 0.8128)
			(layers "F.Cu" "F.Mask" "F.Paste")
			(net "P12V_NIC5_R")
		)
		(pad "16" smd rect
			(at 1.400048 0 90)
			(size 0.254 0.8128)
			(layers "F.Cu" "F.Mask" "F.Paste")
			(net "P12V_NIC5_R")
		)
		(pad "17" smd rect
			(at 1.400048 -0.499872 90)
			(size 0.254 0.8128)
			(layers "F.Cu" "F.Mask" "F.Paste")
			(net "P12V_NIC5_R")
		)
		(pad "18" smd rect
			(at 1.400048 -0.999998 90)
			(size 0.254 0.8128)
			(layers "F.Cu" "F.Mask" "F.Paste")
			(net "P12V_NIC5_R")
		)
		(pad "19" smd rect
			(at 1.400048 -1.500124 90)
			(size 0.254 0.8128)
			(layers "F.Cu" "F.Mask" "F.Paste")
			(net "P12V_NIC5_R")
		)
		(pad "20" smd rect
			(at 1.400048 -1.999996 90)
			(size 0.254 0.8128)
			(layers "F.Cu" "F.Mask" "F.Paste")
			(net "P12V_NIC5_R")
		)
		(pad "21_22" smd circle
			(at 0.499872 -2.337562 90)
			(size 0 0)
			(layers "F.Cu" "F.Mask" "F.Paste")
			(net "P12V_AUX")
		)
		(pad "23" smd rect
			(at 0 -1.100074 90)
			(size 0.254 1.27)
			(layers "F.Cu" "F.Mask" "F.Paste")
			(net "P12V_AUX")
		)
		(pad "24" smd rect
			(at 0 -0.199898 90)
			(size 0.254 1.27)
			(layers "F.Cu" "F.Mask" "F.Paste")
			(net "P12V_AUX")
		)
		(pad "25" smd rect
			(at 0 0.700024 90)
			(size 0.254 1.27)
			(layers "F.Cu" "F.Mask" "F.Paste")
			(net "P12V_AUX")
		)
		(pad "26" smd rect
			(at 0 1.599946 90)
			(size 0.254 1.27)
			(layers "F.Cu" "F.Mask" "F.Paste")
			(net "P12V_AUX")
		)
	)
	(footprint ""
		(layer "F.Cu")
		(at 84.118958 -59.574684 90)
		(property "Reference" "PC529"
			(at 0 0 90)
			(layer "F.SilkS")
			(hide yes)
			(effects
				(font
					(size 1.27 1.27)
				)
			)
		)
		(property "Value" ""
			(at 0 0 90)
			(layer "F.Fab")
			(effects
				(font
					(size 1.27 1.27)
				)
			)
		)
		(duplicate_pad_numbers_are_jumpers no)
		(fp_line
			(start 0.7874 -0.4064)
			(end 0.7874 0.4064)
			(stroke
				(width 0.1524)
				(type default)
			)
			(layer "F.SilkS")
		)
		(fp_line
			(start -0.7874 -0.4064)
			(end 0.7874 -0.4064)
			(stroke
				(width 0.1524)
				(type default)
			)
			(layer "F.SilkS")
		)
		(fp_line
			(start 0.7874 0.4064)
			(end -0.7874 0.4064)
			(stroke
				(width 0.1524)
				(type default)
			)
			(layer "F.SilkS")
		)
		(fp_line
			(start -0.7874 0.4064)
			(end -0.7874 -0.4064)
			(stroke
				(width 0.1524)
				(type default)
			)
			(layer "F.SilkS")
		)
		(fp_line
			(start -0.12065 -0.305054)
			(end -0.12065 -0.2794)
			(stroke
				(width 0.1)
				(type default)
			)
			(layer "F.Fab")
		)
		(fp_line
			(start -0.67945 -0.305054)
			(end -0.12065 -0.305054)
			(stroke
				(width 0.1)
				(type default)
			)
			(layer "F.Fab")
		)
		(fp_line
			(start 0.67945 -0.3048)
			(end 0.67945 0.3048)
			(stroke
				(width 0.1)
				(type default)
			)
			(layer "F.Fab")
		)
		(fp_line
			(start 0.12065 -0.3048)
			(end 0.67945 -0.3048)
			(stroke
				(width 0.1)
				(type default)
			)
			(layer "F.Fab")
		)
		(fp_line
			(start 0.12065 -0.2794)
			(end 0.12065 -0.3048)
			(stroke
				(width 0.1)
				(type default)
			)
			(layer "F.Fab")
		)
		(fp_line
			(start -0.12065 -0.2794)
			(end 0.12065 -0.2794)
			(stroke
				(width 0.1)
				(type default)
			)
			(layer "F.Fab")
		)
		(fp_line
			(start 0.120396 0.2794)
			(end -0.12065 0.2794)
			(stroke
				(width 0.1)
				(type default)
			)
			(layer "F.Fab")
		)
		(fp_line
			(start -0.12065 0.2794)
			(end -0.12065 0.3048)
			(stroke
				(width 0.1)
				(type default)
			)
			(layer "F.Fab")
		)
		(fp_line
			(start 0.67945 0.3048)
			(end 0.120396 0.3048)
			(stroke
				(width 0.1)
				(type default)
			)
			(layer "F.Fab")
		)
		(fp_line
			(start 0.120396 0.3048)
			(end 0.120396 0.2794)
			(stroke
				(width 0.1)
				(type default)
			)
			(layer "F.Fab")
		)
		(fp_line
			(start -0.12065 0.3048)
			(end -0.67945 0.3048)
			(stroke
				(width 0.1)
				(type default)
			)
			(layer "F.Fab")
		)
		(fp_line
			(start -0.67945 0.3048)
			(end -0.67945 -0.305054)
			(stroke
				(width 0.1)
				(type default)
			)
			(layer "F.Fab")
		)
		(pad "1" smd circle
			(at -0.40005 0 90)
			(size 0 0)
			(layers "F.Cu" "F.Mask" "F.Paste")
			(net "P5V_AUX")
		)
		(pad "2" smd circle
			(at 0.40005 0 90)
			(size 0 0)
			(layers "F.Cu" "F.Mask" "F.Paste")
			(net "GND")
		)
	)
	(footprint ""
		(layer "F.Cu")
		(at 48.202088 -343.952322 90)
		(property "Reference" "C166"
			(at 0 0 90)
			(layer "F.SilkS")
			(hide yes)
			(effects
				(font
					(size 1.27 1.27)
				)
			)
		)
		(property "Value" ""
			(at 0 0 90)
			(layer "F.Fab")
			(effects
				(font
					(size 1.27 1.27)
				)
			)
		)
		(duplicate_pad_numbers_are_jumpers no)
		(fp_line
			(start 0.299974 -0.150114)
			(end 0.299974 0.150114)
			(stroke
				(width 0.1)
				(type default)
			)
			(layer "F.Fab")
		)
		(fp_line
			(start -0.299974 -0.150114)
			(end 0.299974 -0.150114)
			(stroke
				(width 0.1)
				(type default)
			)
			(layer "F.Fab")
		)
		(fp_line
			(start 0.299974 0.150114)
			(end -0.299974 0.150114)
			(stroke
				(width 0.1)
				(type default)
			)
			(layer "F.Fab")
		)
		(fp_line
			(start -0.299974 0.150114)
			(end -0.299974 -0.150114)
			(stroke
				(width 0.1)
				(type default)
			)
			(layer "F.Fab")
		)
		(pad "1" smd rect
			(at -0.2667 0 90)
			(size 0.3048 0.381)
			(layers "F.Cu" "F.Mask" "F.Paste")
			(net "P5E_PEX0_STN7_TX_DN<125>")
		)
		(pad "2" smd rect
			(at 0.2667 0 90)
			(size 0.3048 0.381)
			(layers "F.Cu" "F.Mask" "F.Paste")
			(net "P5E_PEX0_STN7_TX_C_DN<125>")
		)
	)
	(footprint ""
		(layer "F.Cu")
		(at 194.367912 -55.083456)
		(property "Reference" "PC372"
			(at 0 0 0)
			(layer "F.SilkS")
			(hide yes)
			(effects
				(font
					(size 1.27 1.27)
				)
			)
		)
		(property "Value" ""
			(at 0 0 0)
			(layer "F.Fab")
			(effects
				(font
					(size 1.27 1.27)
				)
			)
		)
		(duplicate_pad_numbers_are_jumpers no)
		(fp_line
			(start -0.7874 -0.4064)
			(end 0.7874 -0.4064)
			(stroke
				(width 0.1524)
				(type default)
			)
			(layer "F.SilkS")
		)
		(fp_line
			(start -0.7874 0.4064)
			(end -0.7874 -0.4064)
			(stroke
				(width 0.1524)
				(type default)
			)
			(layer "F.SilkS")
		)
		(fp_line
			(start 0.7874 -0.4064)
			(end 0.7874 0.4064)
			(stroke
				(width 0.1524)
				(type default)
			)
			(layer "F.SilkS")
		)
		(fp_line
			(start 0.7874 0.4064)
			(end -0.7874 0.4064)
			(stroke
				(width 0.1524)
				(type default)
			)
			(layer "F.SilkS")
		)
		(fp_line
			(start -0.67945 -0.305054)
			(end -0.12065 -0.305054)
			(stroke
				(width 0.1)
				(type default)
			)
			(layer "F.Fab")
		)
		(fp_line
			(start -0.67945 0.3048)
			(end -0.67945 -0.305054)
			(stroke
				(width 0.1)
				(type default)
			)
			(layer "F.Fab")
		)
		(fp_line
			(start -0.12065 -0.305054)
			(end -0.12065 -0.2794)
			(stroke
				(width 0.1)
				(type default)
			)
			(layer "F.Fab")
		)
		(fp_line
			(start -0.12065 -0.2794)
			(end 0.12065 -0.2794)
			(stroke
				(width 0.1)
				(type default)
			)
			(layer "F.Fab")
		)
		(fp_line
			(start -0.12065 0.2794)
			(end -0.12065 0.3048)
			(stroke
				(width 0.1)
				(type default)
			)
			(layer "F.Fab")
		)
		(fp_line
			(start -0.12065 0.3048)
			(end -0.67945 0.3048)
			(stroke
				(width 0.1)
				(type default)
			)
			(layer "F.Fab")
		)
		(fp_line
			(start 0.120396 0.2794)
			(end -0.12065 0.2794)
			(stroke
				(width 0.1)
				(type default)
			)
			(layer "F.Fab")
		)
		(fp_line
			(start 0.120396 0.3048)
			(end 0.120396 0.2794)
			(stroke
				(width 0.1)
				(type default)
			)
			(layer "F.Fab")
		)
		(fp_line
			(start 0.12065 -0.3048)
			(end 0.67945 -0.3048)
			(stroke
				(width 0.1)
				(type default)
			)
			(layer "F.Fab")
		)
		(fp_line
			(start 0.12065 -0.2794)
			(end 0.12065 -0.3048)
			(stroke
				(width 0.1)
				(type default)
			)
			(layer "F.Fab")
		)
		(fp_line
			(start 0.67945 -0.3048)
			(end 0.67945 0.3048)
			(stroke
				(width 0.1)
				(type default)
			)
			(layer "F.Fab")
		)
		(fp_line
			(start 0.67945 0.3048)
			(end 0.120396 0.3048)
			(stroke
				(width 0.1)
				(type default)
			)
			(layer "F.Fab")
		)
		(pad "1" smd circle
			(at -0.40005 0)
			(size 0 0)
			(layers "F.Cu" "F.Mask" "F.Paste")
			(net "P5V_AUX")
		)
		(pad "2" smd circle
			(at 0.40005 0)
			(size 0 0)
			(layers "F.Cu" "F.Mask" "F.Paste")
			(net "GND")
		)
	)
)
